# T6G (Grand Teton) — schematic netlist excerpt (pin names and nets, part order shuffled) for the footprints in the layout excerpt that follows; sources: Cadence DE-HDL packaged netlist, KiCad conversion of 04192023_DAF0TMB3IC0_F0TG_MB_C_brd_V02_OCP.brd

R404  Q_RES  0 5% CHIP  pkg 0402LF  page 27 : A = JTAG_CPU0_R_TDO ; B = JTAG_CPU0_TDO
C2637  Q_CAP  22UF 4V 20% X6S  pkg C0402  page 70 : A = PVDDIO_P0 ; B = GND

(kicad_pcb
	(version 20260206)
	(generator "pcbnew")
	(generator_version "10.0")
	(general
		(thickness 1.6)
		(legacy_teardrops no)
	)
	(paper "A4")
	(title_block
		(title "04192023_DAF0TMB3IC0_F0TG_MB_C_brd_V02_OCP.brd")
		(comment 1 "Grand Teton / footprints 6966-6967 of 8354")
	)
	(layers
		(0 "F.Cu" signal "TOP")
		(4 "In1.Cu" signal "GND")
		(6 "In2.Cu" signal "IN1")
		(8 "In3.Cu" signal "GND1")
		(10 "In4.Cu" signal "IN2")
		(12 "In5.Cu" signal "GND2")
		(14 "In6.Cu" signal "IN3")
		(16 "In7.Cu" signal "GND3")
		(18 "In8.Cu" signal "VCC")
		(20 "In9.Cu" signal "VCC1")
		(22 "In10.Cu" signal "GND4")
		(24 "In11.Cu" signal "IN4")
		(26 "In12.Cu" signal "GND5")
		(28 "In13.Cu" signal "IN5")
		(30 "In14.Cu" signal "GND6")
		(32 "In15.Cu" signal "IN6")
		(34 "In16.Cu" signal "GND7")
		(2 "B.Cu" signal "BOTTOM")
		(9 "F.Adhes" user "F.Adhesive")
		(11 "B.Adhes" user "B.Adhesive")
		(13 "F.Paste" user "Package Geometry/Pastemask Top")
		(15 "B.Paste" user "Package Geometry/Pastemask Bottom")
		(5 "F.SilkS" user "Ref Des/Silkscreen Top")
		(7 "B.SilkS" user "Ref Des/Silkscreen Bottom")
		(1 "F.Mask" user "Board Geometry/Soldermask Top")
		(3 "B.Mask" user "Board Geometry/Soldermask Bottom")
		(17 "Dwgs.User" user "User.Drawings")
		(19 "Cmts.User" user "User.Comments")
		(21 "Eco1.User" user "User.Eco1")
		(23 "Eco2.User" user "User.Eco2")
		(25 "Edge.Cuts" user "Board Geometry/Outline")
		(27 "Margin" user)
		(31 "F.CrtYd" user "Package Geometry/Place Bound Top")
		(29 "B.CrtYd" user "Package Geometry/Place Bound Bottom")
		(35 "F.Fab" user "Ref Des/Assembly Top")
		(33 "B.Fab" user "Ref Des/Assembly Bottom")
	)
	(footprint ""
		(layer "B.Cu")
		(at 374.186958 -205.101952 90)
		(property "Reference" "R404"
			(at 0 0 90)
			(layer "B.SilkS")
			(hide yes)
			(effects
				(font
					(size 1.27 1.27)
				)
				(justify mirror)
			)
		)
		(property "Value" ""
			(at 0 0 90)
			(layer "B.Fab")
			(effects
				(font
					(size 1.27 1.27)
				)
				(justify mirror)
			)
		)
		(duplicate_pad_numbers_are_jumpers no)
		(fp_line
			(start 0.7874 -0.4064)
			(end -0.7874 -0.4064)
			(stroke
				(width 0.1524)
				(type default)
			)
			(layer "B.SilkS")
		)
		(fp_line
			(start -0.7874 -0.4064)
			(end -0.7874 0.4064)
			(stroke
				(width 0.1524)
				(type default)
			)
			(layer "B.SilkS")
		)
		(fp_line
			(start 0.7874 0.4064)
			(end 0.7874 -0.4064)
			(stroke
				(width 0.1524)
				(type default)
			)
			(layer "B.SilkS")
		)
		(fp_line
			(start -0.7874 0.4064)
			(end 0.7874 0.4064)
			(stroke
				(width 0.1524)
				(type default)
			)
			(layer "B.SilkS")
		)
		(fp_line
			(start 0.67945 -0.305054)
			(end 0.12065 -0.305054)
			(stroke
				(width 0.1)
				(type default)
			)
			(layer "B.Fab")
		)
		(fp_line
			(start 0.12065 -0.305054)
			(end 0.12065 -0.2794)
			(stroke
				(width 0.1)
				(type default)
			)
			(layer "B.Fab")
		)
		(fp_line
			(start -0.12065 -0.3048)
			(end -0.67945 -0.3048)
			(stroke
				(width 0.1)
				(type default)
			)
			(layer "B.Fab")
		)
		(fp_line
			(start -0.67945 -0.3048)
			(end -0.67945 0.3048)
			(stroke
				(width 0.1)
				(type default)
			)
			(layer "B.Fab")
		)
		(fp_line
			(start 0.12065 -0.2794)
			(end -0.12065 -0.2794)
			(stroke
				(width 0.1)
				(type default)
			)
			(layer "B.Fab")
		)
		(fp_line
			(start -0.12065 -0.2794)
			(end -0.12065 -0.3048)
			(stroke
				(width 0.1)
				(type default)
			)
			(layer "B.Fab")
		)
		(fp_line
			(start 0.12065 0.2794)
			(end 0.12065 0.3048)
			(stroke
				(width 0.1)
				(type default)
			)
			(layer "B.Fab")
		)
		(fp_line
			(start -0.120396 0.2794)
			(end 0.12065 0.2794)
			(stroke
				(width 0.1)
				(type default)
			)
			(layer "B.Fab")
		)
		(fp_line
			(start 0.67945 0.3048)
			(end 0.67945 -0.305054)
			(stroke
				(width 0.1)
				(type default)
			)
			(layer "B.Fab")
		)
		(fp_line
			(start 0.12065 0.3048)
			(end 0.67945 0.3048)
			(stroke
				(width 0.1)
				(type default)
			)
			(layer "B.Fab")
		)
		(fp_line
			(start -0.120396 0.3048)
			(end -0.120396 0.2794)
			(stroke
				(width 0.1)
				(type default)
			)
			(layer "B.Fab")
		)
		(fp_line
			(start -0.67945 0.3048)
			(end -0.120396 0.3048)
			(stroke
				(width 0.1)
				(type default)
			)
			(layer "B.Fab")
		)
		(pad "1" smd circle
			(at 0.40005 0 270)
			(size 0 0)
			(layers "B.Cu" "B.Mask" "B.Paste")
			(net "JTAG_CPU0_R_TDO")
		)
		(pad "2" smd circle
			(at -0.40005 0 270)
			(size 0 0)
			(layers "B.Cu" "B.Mask" "B.Paste")
			(net "JTAG_CPU0_TDO")
		)
	)
	(footprint ""
		(layer "B.Cu")
		(at 350.318832 -257.930142 180)
		(property "Reference" "C2637"
			(at 0 0 0)
			(layer "B.SilkS")
			(hide yes)
			(effects
				(font
					(size 1.27 1.27)
				)
				(justify mirror)
			)
		)
		(property "Value" ""
			(at 0 0 0)
			(layer "B.Fab")
			(effects
				(font
					(size 1.27 1.27)
				)
				(justify mirror)
			)
		)
		(duplicate_pad_numbers_are_jumpers no)
		(fp_line
			(start 0.7874 0.4064)
			(end 0.7874 -0.4064)
			(stroke
				(width 0.1524)
				(type default)
			)
			(layer "B.SilkS")
		)
		(fp_line
			(start 0.7874 -0.4064)
			(end -0.7874 -0.4064)
			(stroke
				(width 0.1524)
				(type default)
			)
			(layer "B.SilkS")
		)
		(fp_line
			(start -0.7874 0.4064)
			(end 0.7874 0.4064)
			(stroke
				(width 0.1524)
				(type default)
			)
			(layer "B.SilkS")
		)
		(fp_line
			(start -0.7874 -0.4064)
			(end -0.7874 0.4064)
			(stroke
				(width 0.1524)
				(type default)
			)
			(layer "B.SilkS")
		)
		(fp_line
			(start 0.67945 0.3048)
			(end 0.67945 -0.305054)
			(stroke
				(width 0.1)
				(type default)
			)
			(layer "B.Fab")
		)
		(fp_line
			(start 0.67945 -0.305054)
			(end 0.12065 -0.305054)
			(stroke
				(width 0.1)
				(type default)
			)
			(layer "B.Fab")
		)
		(fp_line
			(start 0.12065 0.3048)
			(end 0.67945 0.3048)
			(stroke
				(width 0.1)
				(type default)
			)
			(layer "B.Fab")
		)
		(fp_line
			(start 0.12065 0.2794)
			(end 0.12065 0.3048)
			(stroke
				(width 0.1)
				(type default)
			)
			(layer "B.Fab")
		)
		(fp_line
			(start 0.12065 -0.2794)
			(end -0.12065 -0.2794)
			(stroke
				(width 0.1)
				(type default)
			)
			(layer "B.Fab")
		)
		(fp_line
			(start 0.12065 -0.305054)
			(end 0.12065 -0.2794)
			(stroke
				(width 0.1)
				(type default)
			)
			(layer "B.Fab")
		)
		(fp_line
			(start -0.120396 0.3048)
			(end -0.120396 0.2794)
			(stroke
				(width 0.1)
				(type default)
			)
			(layer "B.Fab")
		)
		(fp_line
			(start -0.120396 0.2794)
			(end 0.12065 0.2794)
			(stroke
				(width 0.1)
				(type default)
			)
			(layer "B.Fab")
		)
		(fp_line
			(start -0.12065 -0.2794)
			(end -0.12065 -0.3048)
			(stroke
				(width 0.1)
				(type default)
			)
			(layer "B.Fab")
		)
		(fp_line
			(start -0.12065 -0.3048)
			(end -0.67945 -0.3048)
			(stroke
				(width 0.1)
				(type default)
			)
			(layer "B.Fab")
		)
		(fp_line
			(start -0.67945 0.3048)
			(end -0.120396 0.3048)
			(stroke
				(width 0.1)
				(type default)
			)
			(layer "B.Fab")
		)
		(fp_line
			(start -0.67945 -0.3048)
			(end -0.67945 0.3048)
			(stroke
				(width 0.1)
				(type default)
			)
			(layer "B.Fab")
		)
		(pad "1" smd circle
			(at 0.40005 0)
			(size 0 0)
			(layers "B.Cu" "B.Mask" "B.Paste")
			(net "PVDDIO_P0")
		)
		(pad "2" smd circle
			(at -0.40005 0)
			(size 0 0)
			(layers "B.Cu" "B.Mask" "B.Paste")
			(net "GND")
		)
	)
)
